# T6G (Grand Teton) — schematic netlist excerpt (pin names and nets, part order shuffled) for the footprints in the layout excerpt that follows; sources: Cadence DE-HDL packaged netlist, KiCad conversion of 04192023_DAF0TMB3IC0_F0TG_MB_C_brd_V02_OCP.brd

R236  Q_RES  0 5% CHIP  pkg 0402LF  page 82 : A = CPU0_XTRIG_L4 ; B = FM_CPU0_XTRIG_L4
PR6803  Q_RES  1K 1% EMPTY  pkg 0402LF  page 362 : A = P3V3_AUX ; B = P0V9_RETIMER_CPU0_SVID_SDA

(kicad_pcb
	(version 20260206)
	(generator "pcbnew")
	(generator_version "10.0")
	(general
		(thickness 1.6)
		(legacy_teardrops no)
	)
	(paper "A4")
	(title_block
		(title "04192023_DAF0TMB3IC0_F0TG_MB_C_brd_V02_OCP.brd")
		(comment 1 "Grand Teton / footprints 20-21 of 8354")
	)
	(layers
		(0 "F.Cu" signal "TOP")
		(4 "In1.Cu" signal "GND")
		(6 "In2.Cu" signal "IN1")
		(8 "In3.Cu" signal "GND1")
		(10 "In4.Cu" signal "IN2")
		(12 "In5.Cu" signal "GND2")
		(14 "In6.Cu" signal "IN3")
		(16 "In7.Cu" signal "GND3")
		(18 "In8.Cu" signal "VCC")
		(20 "In9.Cu" signal "VCC1")
		(22 "In10.Cu" signal "GND4")
		(24 "In11.Cu" signal "IN4")
		(26 "In12.Cu" signal "GND5")
		(28 "In13.Cu" signal "IN5")
		(30 "In14.Cu" signal "GND6")
		(32 "In15.Cu" signal "IN6")
		(34 "In16.Cu" signal "GND7")
		(2 "B.Cu" signal "BOTTOM")
		(9 "F.Adhes" user "F.Adhesive")
		(11 "B.Adhes" user "B.Adhesive")
		(13 "F.Paste" user "Package Geometry/Pastemask Top")
		(15 "B.Paste" user "Package Geometry/Pastemask Bottom")
		(5 "F.SilkS" user "Ref Des/Silkscreen Top")
		(7 "B.SilkS" user "Ref Des/Silkscreen Bottom")
		(1 "F.Mask" user "Board Geometry/Soldermask Top")
		(3 "B.Mask" user "Board Geometry/Soldermask Bottom")
		(17 "Dwgs.User" user "User.Drawings")
		(19 "Cmts.User" user "User.Comments")
		(21 "Eco1.User" user "User.Eco1")
		(23 "Eco2.User" user "User.Eco2")
		(25 "Edge.Cuts" user "Board Geometry/Outline")
		(27 "Margin" user)
		(31 "F.CrtYd" user "Package Geometry/Place Bound Top")
		(29 "B.CrtYd" user "Package Geometry/Place Bound Bottom")
		(35 "F.Fab" user "Ref Des/Assembly Top")
		(33 "B.Fab" user "Ref Des/Assembly Bottom")
	)
	(footprint ""
		(layer "F.Cu")
		(at 177.673 -100.294948 90)
		(property "Reference" "R236"
			(at 0 0 90)
			(layer "F.SilkS")
			(hide yes)
			(effects
				(font
					(size 1.27 1.27)
				)
			)
		)
		(property "Value" ""
			(at 0 0 90)
			(layer "F.Fab")
			(effects
				(font
					(size 1.27 1.27)
				)
			)
		)
		(duplicate_pad_numbers_are_jumpers no)
		(fp_line
			(start 0.7874 -0.4064)
			(end 0.7874 0.4064)
			(stroke
				(width 0.1524)
				(type default)
			)
			(layer "F.SilkS")
		)
		(fp_line
			(start -0.7874 -0.4064)
			(end 0.7874 -0.4064)
			(stroke
				(width 0.1524)
				(type default)
			)
			(layer "F.SilkS")
		)
		(fp_line
			(start 0.7874 0.4064)
			(end -0.7874 0.4064)
			(stroke
				(width 0.1524)
				(type default)
			)
			(layer "F.SilkS")
		)
		(fp_line
			(start -0.7874 0.4064)
			(end -0.7874 -0.4064)
			(stroke
				(width 0.1524)
				(type default)
			)
			(layer "F.SilkS")
		)
		(fp_line
			(start -0.12065 -0.305054)
			(end -0.12065 -0.2794)
			(stroke
				(width 0.1)
				(type default)
			)
			(layer "F.Fab")
		)
		(fp_line
			(start -0.67945 -0.305054)
			(end -0.12065 -0.305054)
			(stroke
				(width 0.1)
				(type default)
			)
			(layer "F.Fab")
		)
		(fp_line
			(start 0.67945 -0.3048)
			(end 0.67945 0.3048)
			(stroke
				(width 0.1)
				(type default)
			)
			(layer "F.Fab")
		)
		(fp_line
			(start 0.12065 -0.3048)
			(end 0.67945 -0.3048)
			(stroke
				(width 0.1)
				(type default)
			)
			(layer "F.Fab")
		)
		(fp_line
			(start 0.12065 -0.2794)
			(end 0.12065 -0.3048)
			(stroke
				(width 0.1)
				(type default)
			)
			(layer "F.Fab")
		)
		(fp_line
			(start -0.12065 -0.2794)
			(end 0.12065 -0.2794)
			(stroke
				(width 0.1)
				(type default)
			)
			(layer "F.Fab")
		)
		(fp_line
			(start 0.120396 0.2794)
			(end -0.12065 0.2794)
			(stroke
				(width 0.1)
				(type default)
			)
			(layer "F.Fab")
		)
		(fp_line
			(start -0.12065 0.2794)
			(end -0.12065 0.3048)
			(stroke
				(width 0.1)
				(type default)
			)
			(layer "F.Fab")
		)
		(fp_line
			(start 0.67945 0.3048)
			(end 0.120396 0.3048)
			(stroke
				(width 0.1)
				(type default)
			)
			(layer "F.Fab")
		)
		(fp_line
			(start 0.120396 0.3048)
			(end 0.120396 0.2794)
			(stroke
				(width 0.1)
				(type default)
			)
			(layer "F.Fab")
		)
		(fp_line
			(start -0.12065 0.3048)
			(end -0.67945 0.3048)
			(stroke
				(width 0.1)
				(type default)
			)
			(layer "F.Fab")
		)
		(fp_line
			(start -0.67945 0.3048)
			(end -0.67945 -0.305054)
			(stroke
				(width 0.1)
				(type default)
			)
			(layer "F.Fab")
		)
		(pad "1" smd circle
			(at -0.40005 0 90)
			(size 0 0)
			(layers "F.Cu" "F.Mask" "F.Paste")
			(net "CPU0_XTRIG_L4")
		)
		(pad "2" smd circle
			(at 0.40005 0 90)
			(size 0 0)
			(layers "F.Cu" "F.Mask" "F.Paste")
			(net "FM_CPU0_XTRIG_L4")
		)
	)
	(footprint ""
		(layer "F.Cu")
		(at 439.029602 -422.52011)
		(property "Reference" "PR6803"
			(at 0 0 0)
			(layer "F.SilkS")
			(hide yes)
			(effects
				(font
					(size 1.27 1.27)
				)
			)
		)
		(property "Value" ""
			(at 0 0 0)
			(layer "F.Fab")
			(effects
				(font
					(size 1.27 1.27)
				)
			)
		)
		(duplicate_pad_numbers_are_jumpers no)
		(fp_line
			(start -0.7874 -0.4064)
			(end 0.7874 -0.4064)
			(stroke
				(width 0.1524)
				(type default)
			)
			(layer "F.SilkS")
		)
		(fp_line
			(start -0.7874 0.4064)
			(end -0.7874 -0.4064)
			(stroke
				(width 0.1524)
				(type default)
			)
			(layer "F.SilkS")
		)
		(fp_line
			(start 0.7874 -0.4064)
			(end 0.7874 0.4064)
			(stroke
				(width 0.1524)
				(type default)
			)
			(layer "F.SilkS")
		)
		(fp_line
			(start 0.7874 0.4064)
			(end -0.7874 0.4064)
			(stroke
				(width 0.1524)
				(type default)
			)
			(layer "F.SilkS")
		)
		(fp_line
			(start -0.67945 -0.305054)
			(end -0.12065 -0.305054)
			(stroke
				(width 0.1)
				(type default)
			)
			(layer "F.Fab")
		)
		(fp_line
			(start -0.67945 0.3048)
			(end -0.67945 -0.305054)
			(stroke
				(width 0.1)
				(type default)
			)
			(layer "F.Fab")
		)
		(fp_line
			(start -0.12065 -0.305054)
			(end -0.12065 -0.2794)
			(stroke
				(width 0.1)
				(type default)
			)
			(layer "F.Fab")
		)
		(fp_line
			(start -0.12065 -0.2794)
			(end 0.12065 -0.2794)
			(stroke
				(width 0.1)
				(type default)
			)
			(layer "F.Fab")
		)
		(fp_line
			(start -0.12065 0.2794)
			(end -0.12065 0.3048)
			(stroke
				(width 0.1)
				(type default)
			)
			(layer "F.Fab")
		)
		(fp_line
			(start -0.12065 0.3048)
			(end -0.67945 0.3048)
			(stroke
				(width 0.1)
				(type default)
			)
			(layer "F.Fab")
		)
		(fp_line
			(start 0.120396 0.2794)
			(end -0.12065 0.2794)
			(stroke
				(width 0.1)
				(type default)
			)
			(layer "F.Fab")
		)
		(fp_line
			(start 0.120396 0.3048)
			(end 0.120396 0.2794)
			(stroke
				(width 0.1)
				(type default)
			)
			(layer "F.Fab")
		)
		(fp_line
			(start 0.12065 -0.3048)
			(end 0.67945 -0.3048)
			(stroke
				(width 0.1)
				(type default)
			)
			(layer "F.Fab")
		)
		(fp_line
			(start 0.12065 -0.2794)
			(end 0.12065 -0.3048)
			(stroke
				(width 0.1)
				(type default)
			)
			(layer "F.Fab")
		)
		(fp_line
			(start 0.67945 -0.3048)
			(end 0.67945 0.3048)
			(stroke
				(width 0.1)
				(type default)
			)
			(layer "F.Fab")
		)
		(fp_line
			(start 0.67945 0.3048)
			(end 0.120396 0.3048)
			(stroke
				(width 0.1)
				(type default)
			)
			(layer "F.Fab")
		)
		(pad "1" smd circle
			(at -0.40005 0)
			(size 0 0)
			(layers "F.Cu" "F.Mask" "F.Paste")
			(net "P3V3_AUX")
		)
		(pad "2" smd circle
			(at 0.40005 0)
			(size 0 0)
			(layers "F.Cu" "F.Mask" "F.Paste")
			(net "P0V9_RETIMER_CPU0_SVID_SDA")
		)
	)
)
